(kicad_pcb
	(version 20260206)
	(generator "pcbnew")
	(generator_version "10.0")
	(general
		(thickness 1.6)
		(legacy_teardrops no)
	)
	(paper "A4")
	(title_block
		(title "12092022_DA0F0TMDCD0_F0T_Management_Board_D_brd_V3_OCP.brd")
		(comment 1 "Grand Teton / footprints 37-42 of 1440")
	)
	(layers
		(0 "F.Cu" signal "TOP")
		(4 "In1.Cu" signal "GND")
		(6 "In2.Cu" signal "IN1")
		(8 "In3.Cu" signal "GND1")
		(10 "In4.Cu" signal "IN2")
		(12 "In5.Cu" signal "VCC")
		(14 "In6.Cu" signal "VCC1")
		(16 "In7.Cu" signal "IN3")
		(18 "In8.Cu" signal "GND2")
		(20 "In9.Cu" signal "IN4")
		(22 "In10.Cu" signal "GND3")
		(2 "B.Cu" signal "BOTTOM")
		(9 "F.Adhes" user "F.Adhesive")
		(11 "B.Adhes" user "B.Adhesive")
		(13 "F.Paste" user "Package Geometry/Pastemask Top")
		(15 "B.Paste" user "Package Geometry/Pastemask Bottom")
		(5 "F.SilkS" user "Ref Des/Silkscreen Top")
		(7 "B.SilkS" user "Ref Des/Silkscreen Bottom")
		(1 "F.Mask" user "Board Geometry/Soldermask Top")
		(3 "B.Mask" user "Board Geometry/Soldermask Bottom")
		(17 "Dwgs.User" user "User.Drawings")
		(19 "Cmts.User" user "User.Comments")
		(21 "Eco1.User" user "User.Eco1")
		(23 "Eco2.User" user "User.Eco2")
		(25 "Edge.Cuts" user "Board Geometry/Outline")
		(27 "Margin" user)
		(31 "F.CrtYd" user "Package Geometry/Place Bound Top")
		(29 "B.CrtYd" user "Package Geometry/Place Bound Bottom")
		(35 "F.Fab" user "Ref Des/Assembly Top")
		(33 "B.Fab" user "Ref Des/Assembly Bottom")
	)
	(footprint ""
		(layer "F.Cu")
		(at 75.25004 -36.298378 180)
		(property "Reference" "C17"
			(at 0 0 180)
			(layer "F.SilkS")
			(hide yes)
			(effects
				(font
					(size 1.27 1.27)
				)
			)
		)
		(property "Value" ""
			(at 0 0 180)
			(layer "F.Fab")
			(effects
				(font
					(size 1.27 1.27)
				)
			)
		)
		(duplicate_pad_numbers_are_jumpers no)
		(fp_line
			(start 0.7874 0.4064)
			(end -0.7874 0.4064)
			(stroke
				(width 0.1524)
				(type default)
			)
			(layer "F.SilkS")
		)
		(fp_line
			(start 0.7874 -0.4064)
			(end 0.7874 0.4064)
			(stroke
				(width 0.1524)
				(type default)
			)
			(layer "F.SilkS")
		)
		(fp_line
			(start -0.7874 0.4064)
			(end -0.7874 -0.4064)
			(stroke
				(width 0.1524)
				(type default)
			)
			(layer "F.SilkS")
		)
		(fp_line
			(start -0.7874 -0.4064)
			(end 0.7874 -0.4064)
			(stroke
				(width 0.1524)
				(type default)
			)
			(layer "F.SilkS")
		)
		(fp_line
			(start 0.67945 0.3048)
			(end 0.120396 0.3048)
			(stroke
				(width 0.1)
				(type default)
			)
			(layer "F.Fab")
		)
		(fp_line
			(start 0.67945 -0.3048)
			(end 0.67945 0.3048)
			(stroke
				(width 0.1)
				(type default)
			)
			(layer "F.Fab")
		)
		(fp_line
			(start 0.12065 -0.2794)
			(end 0.12065 -0.3048)
			(stroke
				(width 0.1)
				(type default)
			)
			(layer "F.Fab")
		)
		(fp_line
			(start 0.12065 -0.3048)
			(end 0.67945 -0.3048)
			(stroke
				(width 0.1)
				(type default)
			)
			(layer "F.Fab")
		)
		(fp_line
			(start 0.120396 0.3048)
			(end 0.120396 0.2794)
			(stroke
				(width 0.1)
				(type default)
			)
			(layer "F.Fab")
		)
		(fp_line
			(start 0.120396 0.2794)
			(end -0.12065 0.2794)
			(stroke
				(width 0.1)
				(type default)
			)
			(layer "F.Fab")
		)
		(fp_line
			(start -0.12065 0.3048)
			(end -0.67945 0.3048)
			(stroke
				(width 0.1)
				(type default)
			)
			(layer "F.Fab")
		)
		(fp_line
			(start -0.12065 0.2794)
			(end -0.12065 0.3048)
			(stroke
				(width 0.1)
				(type default)
			)
			(layer "F.Fab")
		)
		(fp_line
			(start -0.12065 -0.2794)
			(end 0.12065 -0.2794)
			(stroke
				(width 0.1)
				(type default)
			)
			(layer "F.Fab")
		)
		(fp_line
			(start -0.12065 -0.305054)
			(end -0.12065 -0.2794)
			(stroke
				(width 0.1)
				(type default)
			)
			(layer "F.Fab")
		)
		(fp_line
			(start -0.67945 0.3048)
			(end -0.67945 -0.305054)
			(stroke
				(width 0.1)
				(type default)
			)
			(layer "F.Fab")
		)
		(fp_line
			(start -0.67945 -0.305054)
			(end -0.12065 -0.305054)
			(stroke
				(width 0.1)
				(type default)
			)
			(layer "F.Fab")
		)
		(pad "1" smd circle
			(at -0.40005 0 180)
			(size 0 0)
			(layers "F.Cu" "F.Mask" "F.Paste")
			(net "P1V2_AUX")
		)
		(pad "2" smd circle
			(at 0.40005 0 180)
			(size 0 0)
			(layers "F.Cu" "F.Mask" "F.Paste")
			(net "GND")
		)
	)
	(footprint ""
		(layer "F.Cu")
		(at 29.6164 -27.3304 180)
		(property "Reference" "R17"
			(at 0 0 180)
			(layer "F.SilkS")
			(hide yes)
			(effects
				(font
					(size 1.27 1.27)
				)
			)
		)
		(property "Value" ""
			(at 0 0 180)
			(layer "F.Fab")
			(effects
				(font
					(size 1.27 1.27)
				)
			)
		)
		(duplicate_pad_numbers_are_jumpers no)
		(fp_line
			(start 0.7874 0.4064)
			(end -0.7874 0.4064)
			(stroke
				(width 0.1524)
				(type default)
			)
			(layer "F.SilkS")
		)
		(fp_line
			(start 0.7874 -0.4064)
			(end 0.7874 0.4064)
			(stroke
				(width 0.1524)
				(type default)
			)
			(layer "F.SilkS")
		)
		(fp_line
			(start -0.7874 0.4064)
			(end -0.7874 -0.4064)
			(stroke
				(width 0.1524)
				(type default)
			)
			(layer "F.SilkS")
		)
		(fp_line
			(start -0.7874 -0.4064)
			(end 0.7874 -0.4064)
			(stroke
				(width 0.1524)
				(type default)
			)
			(layer "F.SilkS")
		)
		(fp_line
			(start 0.67945 0.3048)
			(end 0.120396 0.3048)
			(stroke
				(width 0.1)
				(type default)
			)
			(layer "F.Fab")
		)
		(fp_line
			(start 0.67945 -0.3048)
			(end 0.67945 0.3048)
			(stroke
				(width 0.1)
				(type default)
			)
			(layer "F.Fab")
		)
		(fp_line
			(start 0.12065 -0.2794)
			(end 0.12065 -0.3048)
			(stroke
				(width 0.1)
				(type default)
			)
			(layer "F.Fab")
		)
		(fp_line
			(start 0.12065 -0.3048)
			(end 0.67945 -0.3048)
			(stroke
				(width 0.1)
				(type default)
			)
			(layer "F.Fab")
		)
		(fp_line
			(start 0.120396 0.3048)
			(end 0.120396 0.2794)
			(stroke
				(width 0.1)
				(type default)
			)
			(layer "F.Fab")
		)
		(fp_line
			(start 0.120396 0.2794)
			(end -0.12065 0.2794)
			(stroke
				(width 0.1)
				(type default)
			)
			(layer "F.Fab")
		)
		(fp_line
			(start -0.12065 0.3048)
			(end -0.67945 0.3048)
			(stroke
				(width 0.1)
				(type default)
			)
			(layer "F.Fab")
		)
		(fp_line
			(start -0.12065 0.2794)
			(end -0.12065 0.3048)
			(stroke
				(width 0.1)
				(type default)
			)
			(layer "F.Fab")
		)
		(fp_line
			(start -0.12065 -0.2794)
			(end 0.12065 -0.2794)
			(stroke
				(width 0.1)
				(type default)
			)
			(layer "F.Fab")
		)
		(fp_line
			(start -0.12065 -0.305054)
			(end -0.12065 -0.2794)
			(stroke
				(width 0.1)
				(type default)
			)
			(layer "F.Fab")
		)
		(fp_line
			(start -0.67945 0.3048)
			(end -0.67945 -0.305054)
			(stroke
				(width 0.1)
				(type default)
			)
			(layer "F.Fab")
		)
		(fp_line
			(start -0.67945 -0.305054)
			(end -0.12065 -0.305054)
			(stroke
				(width 0.1)
				(type default)
			)
			(layer "F.Fab")
		)
		(pad "1" smd circle
			(at -0.40005 0 180)
			(size 0 0)
			(layers "F.Cu" "F.Mask" "F.Paste")
			(net "V_BMC_LS_DDC_SDA_R")
		)
		(pad "2" smd circle
			(at 0.40005 0 180)
			(size 0 0)
			(layers "F.Cu" "F.Mask" "F.Paste")
			(net "CRT_VCC5")
		)
	)
	(footprint ""
		(layer "F.Cu")
		(at 61.8998 -27.3304 -90)
		(property "Reference" "R273"
			(at 0 0 270)
			(layer "F.SilkS")
			(hide yes)
			(effects
				(font
					(size 1.27 1.27)
				)
			)
		)
		(property "Value" ""
			(at 0 0 270)
			(layer "F.Fab")
			(effects
				(font
					(size 1.27 1.27)
				)
			)
		)
		(duplicate_pad_numbers_are_jumpers no)
		(fp_line
			(start -0.7874 0.4064)
			(end -0.7874 -0.4064)
			(stroke
				(width 0.1524)
				(type default)
			)
			(layer "F.SilkS")
		)
		(fp_line
			(start 0.7874 0.4064)
			(end -0.7874 0.4064)
			(stroke
				(width 0.1524)
				(type default)
			)
			(layer "F.SilkS")
		)
		(fp_line
			(start -0.7874 -0.4064)
			(end 0.7874 -0.4064)
			(stroke
				(width 0.1524)
				(type default)
			)
			(layer "F.SilkS")
		)
		(fp_line
			(start 0.7874 -0.4064)
			(end 0.7874 0.4064)
			(stroke
				(width 0.1524)
				(type default)
			)
			(layer "F.SilkS")
		)
		(fp_line
			(start -0.67945 0.3048)
			(end -0.67945 -0.305054)
			(stroke
				(width 0.1)
				(type default)
			)
			(layer "F.Fab")
		)
		(fp_line
			(start -0.12065 0.3048)
			(end -0.67945 0.3048)
			(stroke
				(width 0.1)
				(type default)
			)
			(layer "F.Fab")
		)
		(fp_line
			(start 0.120396 0.3048)
			(end 0.120396 0.2794)
			(stroke
				(width 0.1)
				(type default)
			)
			(layer "F.Fab")
		)
		(fp_line
			(start 0.67945 0.3048)
			(end 0.120396 0.3048)
			(stroke
				(width 0.1)
				(type default)
			)
			(layer "F.Fab")
		)
		(fp_line
			(start -0.12065 0.2794)
			(end -0.12065 0.3048)
			(stroke
				(width 0.1)
				(type default)
			)
			(layer "F.Fab")
		)
		(fp_line
			(start 0.120396 0.2794)
			(end -0.12065 0.2794)
			(stroke
				(width 0.1)
				(type default)
			)
			(layer "F.Fab")
		)
		(fp_line
			(start -0.12065 -0.2794)
			(end 0.12065 -0.2794)
			(stroke
				(width 0.1)
				(type default)
			)
			(layer "F.Fab")
		)
		(fp_line
			(start 0.12065 -0.2794)
			(end 0.12065 -0.3048)
			(stroke
				(width 0.1)
				(type default)
			)
			(layer "F.Fab")
		)
		(fp_line
			(start 0.12065 -0.3048)
			(end 0.67945 -0.3048)
			(stroke
				(width 0.1)
				(type default)
			)
			(layer "F.Fab")
		)
		(fp_line
			(start 0.67945 -0.3048)
			(end 0.67945 0.3048)
			(stroke
				(width 0.1)
				(type default)
			)
			(layer "F.Fab")
		)
		(fp_line
			(start -0.67945 -0.305054)
			(end -0.12065 -0.305054)
			(stroke
				(width 0.1)
				(type default)
			)
			(layer "F.Fab")
		)
		(fp_line
			(start -0.12065 -0.305054)
			(end -0.12065 -0.2794)
			(stroke
				(width 0.1)
				(type default)
			)
			(layer "F.Fab")
		)
		(pad "1" smd circle
			(at -0.40005 0 270)
			(size 0 0)
			(layers "F.Cu" "F.Mask" "F.Paste")
			(net "PD_CLK_125M_PHY_BMC_RGMII")
		)
		(pad "2" smd circle
			(at 0.40005 0 270)
			(size 0 0)
			(layers "F.Cu" "F.Mask" "F.Paste")
			(net "GND")
		)
	)
	(footprint ""
		(layer "F.Cu")
		(at 15.548864 -57.7342 90)
		(property "Reference" "R902"
			(at 0 0 90)
			(layer "F.SilkS")
			(hide yes)
			(effects
				(font
					(size 1.27 1.27)
				)
			)
		)
		(property "Value" ""
			(at 0 0 90)
			(layer "F.Fab")
			(effects
				(font
					(size 1.27 1.27)
				)
			)
		)
		(duplicate_pad_numbers_are_jumpers no)
		(fp_line
			(start 0.7874 -0.4064)
			(end 0.7874 0.4064)
			(stroke
				(width 0.1524)
				(type default)
			)
			(layer "F.SilkS")
		)
		(fp_line
			(start -0.7874 -0.4064)
			(end 0.7874 -0.4064)
			(stroke
				(width 0.1524)
				(type default)
			)
			(layer "F.SilkS")
		)
		(fp_line
			(start 0.7874 0.4064)
			(end -0.7874 0.4064)
			(stroke
				(width 0.1524)
				(type default)
			)
			(layer "F.SilkS")
		)
		(fp_line
			(start -0.7874 0.4064)
			(end -0.7874 -0.4064)
			(stroke
				(width 0.1524)
				(type default)
			)
			(layer "F.SilkS")
		)
		(fp_line
			(start -0.12065 -0.305054)
			(end -0.12065 -0.2794)
			(stroke
				(width 0.1)
				(type default)
			)
			(layer "F.Fab")
		)
		(fp_line
			(start -0.67945 -0.305054)
			(end -0.12065 -0.305054)
			(stroke
				(width 0.1)
				(type default)
			)
			(layer "F.Fab")
		)
		(fp_line
			(start 0.67945 -0.3048)
			(end 0.67945 0.3048)
			(stroke
				(width 0.1)
				(type default)
			)
			(layer "F.Fab")
		)
		(fp_line
			(start 0.12065 -0.3048)
			(end 0.67945 -0.3048)
			(stroke
				(width 0.1)
				(type default)
			)
			(layer "F.Fab")
		)
		(fp_line
			(start 0.12065 -0.2794)
			(end 0.12065 -0.3048)
			(stroke
				(width 0.1)
				(type default)
			)
			(layer "F.Fab")
		)
		(fp_line
			(start -0.12065 -0.2794)
			(end 0.12065 -0.2794)
			(stroke
				(width 0.1)
				(type default)
			)
			(layer "F.Fab")
		)
		(fp_line
			(start 0.120396 0.2794)
			(end -0.12065 0.2794)
			(stroke
				(width 0.1)
				(type default)
			)
			(layer "F.Fab")
		)
		(fp_line
			(start -0.12065 0.2794)
			(end -0.12065 0.3048)
			(stroke
				(width 0.1)
				(type default)
			)
			(layer "F.Fab")
		)
		(fp_line
			(start 0.67945 0.3048)
			(end 0.120396 0.3048)
			(stroke
				(width 0.1)
				(type default)
			)
			(layer "F.Fab")
		)
		(fp_line
			(start 0.120396 0.3048)
			(end 0.120396 0.2794)
			(stroke
				(width 0.1)
				(type default)
			)
			(layer "F.Fab")
		)
		(fp_line
			(start -0.12065 0.3048)
			(end -0.67945 0.3048)
			(stroke
				(width 0.1)
				(type default)
			)
			(layer "F.Fab")
		)
		(fp_line
			(start -0.67945 0.3048)
			(end -0.67945 -0.305054)
			(stroke
				(width 0.1)
				(type default)
			)
			(layer "F.Fab")
		)
		(pad "1" smd circle
			(at -0.40005 0 90)
			(size 0 0)
			(layers "F.Cu" "F.Mask" "F.Paste")
			(net "UART_BIC_DBG_RX")
		)
		(pad "2" smd circle
			(at 0.40005 0 90)
			(size 0 0)
			(layers "F.Cu" "F.Mask" "F.Paste")
			(net "UART_BIC_DBG_RX_R")
		)
	)
	(footprint ""
		(layer "F.Cu")
		(at 29.845 -105.41 180)
		(property "Reference" "R633"
			(at 0 0 180)
			(layer "F.SilkS")
			(hide yes)
			(effects
				(font
					(size 1.27 1.27)
				)
			)
		)
		(property "Value" ""
			(at 0 0 180)
			(layer "F.Fab")
			(effects
				(font
					(size 1.27 1.27)
				)
			)
		)
		(duplicate_pad_numbers_are_jumpers no)
		(fp_line
			(start 0.7874 0.4064)
			(end -0.7874 0.4064)
			(stroke
				(width 0.1524)
				(type default)
			)
			(layer "F.SilkS")
		)
		(fp_line
			(start 0.7874 -0.4064)
			(end 0.7874 0.4064)
			(stroke
				(width 0.1524)
				(type default)
			)
			(layer "F.SilkS")
		)
		(fp_line
			(start -0.7874 0.4064)
			(end -0.7874 -0.4064)
			(stroke
				(width 0.1524)
				(type default)
			)
			(layer "F.SilkS")
		)
		(fp_line
			(start -0.7874 -0.4064)
			(end 0.7874 -0.4064)
			(stroke
				(width 0.1524)
				(type default)
			)
			(layer "F.SilkS")
		)
		(fp_line
			(start 0.67945 0.3048)
			(end 0.120396 0.3048)
			(stroke
				(width 0.1)
				(type default)
			)
			(layer "F.Fab")
		)
		(fp_line
			(start 0.67945 -0.3048)
			(end 0.67945 0.3048)
			(stroke
				(width 0.1)
				(type default)
			)
			(layer "F.Fab")
		)
		(fp_line
			(start 0.12065 -0.2794)
			(end 0.12065 -0.3048)
			(stroke
				(width 0.1)
				(type default)
			)
			(layer "F.Fab")
		)
		(fp_line
			(start 0.12065 -0.3048)
			(end 0.67945 -0.3048)
			(stroke
				(width 0.1)
				(type default)
			)
			(layer "F.Fab")
		)
		(fp_line
			(start 0.120396 0.3048)
			(end 0.120396 0.2794)
			(stroke
				(width 0.1)
				(type default)
			)
			(layer "F.Fab")
		)
		(fp_line
			(start 0.120396 0.2794)
			(end -0.12065 0.2794)
			(stroke
				(width 0.1)
				(type default)
			)
			(layer "F.Fab")
		)
		(fp_line
			(start -0.12065 0.3048)
			(end -0.67945 0.3048)
			(stroke
				(width 0.1)
				(type default)
			)
			(layer "F.Fab")
		)
		(fp_line
			(start -0.12065 0.2794)
			(end -0.12065 0.3048)
			(stroke
				(width 0.1)
				(type default)
			)
			(layer "F.Fab")
		)
		(fp_line
			(start -0.12065 -0.2794)
			(end 0.12065 -0.2794)
			(stroke
				(width 0.1)
				(type default)
			)
			(layer "F.Fab")
		)
		(fp_line
			(start -0.12065 -0.305054)
			(end -0.12065 -0.2794)
			(stroke
				(width 0.1)
				(type default)
			)
			(layer "F.Fab")
		)
		(fp_line
			(start -0.67945 0.3048)
			(end -0.67945 -0.305054)
			(stroke
				(width 0.1)
				(type default)
			)
			(layer "F.Fab")
		)
		(fp_line
			(start -0.67945 -0.305054)
			(end -0.12065 -0.305054)
			(stroke
				(width 0.1)
				(type default)
			)
			(layer "F.Fab")
		)
		(pad "1" smd circle
			(at -0.40005 0 180)
			(size 0 0)
			(layers "F.Cu" "F.Mask" "F.Paste")
			(net "P3V3_AUX")
		)
		(pad "2" smd circle
			(at 0.40005 0 180)
			(size 0 0)
			(layers "F.Cu" "F.Mask" "F.Paste")
			(net "RST_BMC_HW_OUT")
		)
	)
	(footprint ""
		(layer "F.Cu")
		(at 15.26286 -31.66364 90)
		(property "Reference" "R878"
			(at 0 0 90)
			(layer "F.SilkS")
			(hide yes)
			(effects
				(font
					(size 1.27 1.27)
				)
			)
		)
		(property "Value" ""
			(at 0 0 90)
			(layer "F.Fab")
			(effects
				(font
					(size 1.27 1.27)
				)
			)
		)
		(duplicate_pad_numbers_are_jumpers no)
		(fp_line
			(start 0.7874 -0.4064)
			(end 0.7874 0.4064)
			(stroke
				(width 0.1524)
				(type default)
			)
			(layer "F.SilkS")
		)
		(fp_line
			(start -0.7874 -0.4064)
			(end 0.7874 -0.4064)
			(stroke
				(width 0.1524)
				(type default)
			)
			(layer "F.SilkS")
		)
		(fp_line
			(start 0.7874 0.4064)
			(end -0.7874 0.4064)
			(stroke
				(width 0.1524)
				(type default)
			)
			(layer "F.SilkS")
		)
		(fp_line
			(start -0.7874 0.4064)
			(end -0.7874 -0.4064)
			(stroke
				(width 0.1524)
				(type default)
			)
			(layer "F.SilkS")
		)
		(fp_line
			(start -0.12065 -0.305054)
			(end -0.12065 -0.2794)
			(stroke
				(width 0.1)
				(type default)
			)
			(layer "F.Fab")
		)
		(fp_line
			(start -0.67945 -0.305054)
			(end -0.12065 -0.305054)
			(stroke
				(width 0.1)
				(type default)
			)
			(layer "F.Fab")
		)
		(fp_line
			(start 0.67945 -0.3048)
			(end 0.67945 0.3048)
			(stroke
				(width 0.1)
				(type default)
			)
			(layer "F.Fab")
		)
		(fp_line
			(start 0.12065 -0.3048)
			(end 0.67945 -0.3048)
			(stroke
				(width 0.1)
				(type default)
			)
			(layer "F.Fab")
		)
		(fp_line
			(start 0.12065 -0.2794)
			(end 0.12065 -0.3048)
			(stroke
				(width 0.1)
				(type default)
			)
			(layer "F.Fab")
		)
		(fp_line
			(start -0.12065 -0.2794)
			(end 0.12065 -0.2794)
			(stroke
				(width 0.1)
				(type default)
			)
			(layer "F.Fab")
		)
		(fp_line
			(start 0.120396 0.2794)
			(end -0.12065 0.2794)
			(stroke
				(width 0.1)
				(type default)
			)
			(layer "F.Fab")
		)
		(fp_line
			(start -0.12065 0.2794)
			(end -0.12065 0.3048)
			(stroke
				(width 0.1)
				(type default)
			)
			(layer "F.Fab")
		)
		(fp_line
			(start 0.67945 0.3048)
			(end 0.120396 0.3048)
			(stroke
				(width 0.1)
				(type default)
			)
			(layer "F.Fab")
		)
		(fp_line
			(start 0.120396 0.3048)
			(end 0.120396 0.2794)
			(stroke
				(width 0.1)
				(type default)
			)
			(layer "F.Fab")
		)
		(fp_line
			(start -0.12065 0.3048)
			(end -0.67945 0.3048)
			(stroke
				(width 0.1)
				(type default)
			)
			(layer "F.Fab")
		)
		(fp_line
			(start -0.67945 0.3048)
			(end -0.67945 -0.305054)
			(stroke
				(width 0.1)
				(type default)
			)
			(layer "F.Fab")
		)
		(pad "1" smd circle
			(at -0.40005 0 90)
			(size 0 0)
			(layers "F.Cu" "F.Mask" "F.Paste")
			(net "PWRGD_P1V2_AUX_R2")
		)
		(pad "2" smd circle
			(at 0.40005 0 90)
			(size 0 0)
			(layers "F.Cu" "F.Mask" "F.Paste")
			(net "EN_P1V0_AUX_R")
		)
	)
)
